# S9S_MB_2U (Grand Teton) — schematic netlist excerpt (pin names and nets, part order shuffled) for the footprints in the layout excerpt that follows; sources: Cadence DE-HDL packaged netlist, KiCad conversion of 03242023_DA0F0TMBIJ0_F0T_Motherboard_J_brd_V01_OCP.brd

X34  TP_TDR_4P_FTS  TP_TDR_4P_DIP EMPTY  pkg TH  page 310
  S1  = UNNAMED_310_TPTDR4PFTS_I19_S1
  P1  = T1_GND
  P2  = T1_GND
  S2  = UNNAMED_310_TPTDR4PFTS_I19_S2

PC393  Q_CAP  470PF 50V 10% X7R  pkg 0402  page 296 : A = PVCCD_HV_CPU1_ATSEN ; B = GND

(kicad_pcb
	(version 20260206)
	(generator "pcbnew")
	(generator_version "10.0")
	(general
		(thickness 1.6)
		(legacy_teardrops no)
	)
	(paper "A4")
	(title_block
		(title "03242023_DA0F0TMBIJ0_F0T_Motherboard_J_brd_V01_OCP.brd")
		(comment 1 "Grand Teton / footprints 519-520 of 6105")
	)
	(layers
		(0 "F.Cu" signal "TOP")
		(4 "In1.Cu" signal "GND")
		(6 "In2.Cu" signal "IN1")
		(8 "In3.Cu" signal "GND1")
		(10 "In4.Cu" signal "IN2")
		(12 "In5.Cu" signal "GND2")
		(14 "In6.Cu" signal "IN3")
		(16 "In7.Cu" signal "GND3")
		(18 "In8.Cu" signal "VCC")
		(20 "In9.Cu" signal "VCC1")
		(22 "In10.Cu" signal "GND4")
		(24 "In11.Cu" signal "IN4")
		(26 "In12.Cu" signal "GND5")
		(28 "In13.Cu" signal "IN5")
		(30 "In14.Cu" signal "GND6")
		(32 "In15.Cu" signal "IN6")
		(34 "In16.Cu" signal "GND7")
		(2 "B.Cu" signal "BOTTOM")
		(9 "F.Adhes" user "F.Adhesive")
		(11 "B.Adhes" user "B.Adhesive")
		(13 "F.Paste" user "Package Geometry/Pastemask Top")
		(15 "B.Paste" user "Package Geometry/Pastemask Bottom")
		(5 "F.SilkS" user "Ref Des/Silkscreen Top")
		(7 "B.SilkS" user "Ref Des/Silkscreen Bottom")
		(1 "F.Mask" user "Board Geometry/Soldermask Top")
		(3 "B.Mask" user "Board Geometry/Soldermask Bottom")
		(17 "Dwgs.User" user "User.Drawings")
		(19 "Cmts.User" user "User.Comments")
		(21 "Eco1.User" user "User.Eco1")
		(23 "Eco2.User" user "User.Eco2")
		(25 "Edge.Cuts" user "Board Geometry/Outline")
		(27 "Margin" user)
		(31 "F.CrtYd" user "Package Geometry/Place Bound Top")
		(29 "B.CrtYd" user "Package Geometry/Place Bound Bottom")
		(35 "F.Fab" user "Ref Des/Assembly Top")
		(33 "B.Fab" user "Ref Des/Assembly Bottom")
	)
	(footprint ""
		(layer "F.Cu")
		(at 482.66985 -242.495832 90)
		(property "Reference" "X34"
			(at -0.1778 -1.92913 90)
			(unlocked yes)
			(layer "F.SilkS")
			(effects
				(font
					(size 0.7874 0.5842)
					(thickness 0.1524)
				)
				(justify left)
			)
		)
		(property "Value" ""
			(at 0 0 90)
			(layer "F.Fab")
			(effects
				(font
					(size 1.27 1.27)
				)
			)
		)
		(property "Device Type" "TP_TDR_4P_FTS_TH-TP_TDR_4P_DIPA"
			(at 1.30175 1.27 180)
			(unlocked yes)
			(layer "F.Fab")
			(hide yes)
			(effects
				(font
					(size 0.635 0.4064)
					(thickness 0.1524)
				)
			)
		)
		(property "User Part Number" "N_A"
			(at 1.30175 1.27 180)
			(unlocked yes)
			(layer "Cmts.User")
			(hide yes)
			(effects
				(font
					(size 0.635 0.4064)
					(thickness 0.1524)
				)
			)
		)
		(duplicate_pad_numbers_are_jumpers no)
		(fp_line
			(start 2.54 -1.27)
			(end 0 -1.27)
			(stroke
				(width 0.1524)
				(type default)
			)
			(layer "F.SilkS")
		)
		(fp_line
			(start 0 -1.27)
			(end 0 -0.635)
			(stroke
				(width 0.1524)
				(type default)
			)
			(layer "F.SilkS")
		)
		(fp_line
			(start 2.54 -1.1303)
			(end 2.54 -1.27)
			(stroke
				(width 0.1524)
				(type default)
			)
			(layer "F.SilkS")
		)
		(fp_line
			(start 0 0.635)
			(end 0 1.905)
			(stroke
				(width 0.1524)
				(type default)
			)
			(layer "F.SilkS")
		)
		(fp_line
			(start 2.54 1.4097)
			(end 2.54 1.1303)
			(stroke
				(width 0.1524)
				(type default)
			)
			(layer "F.SilkS")
		)
		(fp_line
			(start 0 3.175)
			(end 0 3.81)
			(stroke
				(width 0.1524)
				(type default)
			)
			(layer "F.SilkS")
		)
		(fp_line
			(start 2.54 3.81)
			(end 2.54 3.6703)
			(stroke
				(width 0.1524)
				(type default)
			)
			(layer "F.SilkS")
		)
		(fp_line
			(start 0 3.81)
			(end 2.54 3.81)
			(stroke
				(width 0.1524)
				(type default)
			)
			(layer "F.SilkS")
		)
		(fp_poly
			(pts
				(xy -0.761746 0) (xy -2.285746 -0.762) (xy -2.285746 0.762)
			)
			(stroke
				(width 0)
				(type default)
			)
			(fill yes)
			(layer "F.SilkS")
		)
		(fp_line
			(start 2.54 -1.27)
			(end 0 -1.27)
			(stroke
				(width 0.1)
				(type default)
			)
			(layer "F.Fab")
		)
		(fp_line
			(start 0 -1.27)
			(end 0 3.81)
			(stroke
				(width 0.1)
				(type default)
			)
			(layer "F.Fab")
		)
		(fp_line
			(start 2.54 3.81)
			(end 2.54 -1.27)
			(stroke
				(width 0.1)
				(type default)
			)
			(layer "F.Fab")
		)
		(fp_line
			(start 0 3.81)
			(end 2.54 3.81)
			(stroke
				(width 0.1)
				(type default)
			)
			(layer "F.Fab")
		)
		(fp_poly
			(pts
				(xy -0.761746 0) (xy -2.285746 -0.762) (xy -2.285746 0.762)
			)
			(stroke
				(width 0)
				(type default)
			)
			(fill yes)
			(layer "F.Fab")
		)
		(pad "1" thru_hole circle
			(at 0 0 90)
			(size 1.0033 1.0033)
			(drill 0.249936)
			(layers "*.Cu" "*.Mask")
			(remove_unused_layers no)
			(net "TDR_DIFF_85_NECK_IN1_DP")
			(clearance 0.10795)
			(thermal_gap 0.10795)
			(padstack
				(mode front_inner_back)
				(layer "Inner"
					(shape circle)
					(size 0.8001 0.8001)
					(clearance 0.1524)
				)
				(layer "B.Cu"
					(shape circle)
					(size 1.0033 1.0033)
					(clearance 0.10795)
				)
			)
		)
		(pad "2" thru_hole circle
			(at 2.54 0 90)
			(size 1.9939 1.9939)
			(drill 0.249936)
			(layers "*.Cu" "*.Mask")
			(remove_unused_layers no)
			(net "T1_GND")
			(clearance 0.10795)
			(thermal_gap 0.10795)
			(padstack
				(mode front_inner_back)
				(layer "Inner"
					(shape circle)
					(size 0.8001 0.8001)
					(clearance 0.1524)
				)
				(layer "B.Cu"
					(shape circle)
					(size 1.9939 1.9939)
					(clearance 0.10795)
				)
			)
		)
		(pad "3" thru_hole circle
			(at 2.54 2.54 90)
			(size 1.9939 1.9939)
			(drill 0.249936)
			(layers "*.Cu" "*.Mask")
			(remove_unused_layers no)
			(net "T1_GND")
			(clearance 0.10795)
			(thermal_gap 0.10795)
			(padstack
				(mode front_inner_back)
				(layer "Inner"
					(shape circle)
					(size 0.8001 0.8001)
					(clearance 0.1524)
				)
				(layer "B.Cu"
					(shape circle)
					(size 1.9939 1.9939)
					(clearance 0.10795)
				)
			)
		)
		(pad "4" thru_hole circle
			(at 0 2.54 90)
			(size 1.0033 1.0033)
			(drill 0.249936)
			(layers "*.Cu" "*.Mask")
			(remove_unused_layers no)
			(net "TDR_DIFF_85_NECK_IN1_DN")
			(clearance 0.10795)
			(thermal_gap 0.10795)
			(padstack
				(mode front_inner_back)
				(layer "Inner"
					(shape circle)
					(size 0.8001 0.8001)
					(clearance 0.1524)
				)
				(layer "B.Cu"
					(shape circle)
					(size 1.0033 1.0033)
					(clearance 0.10795)
				)
			)
		)
	)
	(footprint ""
		(layer "F.Cu")
		(at 31.937452 -164.364162)
		(property "Reference" "PC393"
			(at 0 0 0)
			(layer "F.SilkS")
			(hide yes)
			(effects
				(font
					(size 1.27 1.27)
				)
			)
		)
		(property "Value" ""
			(at 0 0 0)
			(layer "F.Fab")
			(effects
				(font
					(size 1.27 1.27)
				)
			)
		)
		(duplicate_pad_numbers_are_jumpers no)
		(fp_line
			(start -0.7874 -0.4064)
			(end 0.7874 -0.4064)
			(stroke
				(width 0.1524)
				(type default)
			)
			(layer "F.SilkS")
		)
		(fp_line
			(start -0.7874 0.4064)
			(end -0.7874 -0.4064)
			(stroke
				(width 0.1524)
				(type default)
			)
			(layer "F.SilkS")
		)
		(fp_line
			(start 0.7874 -0.4064)
			(end 0.7874 0.4064)
			(stroke
				(width 0.1524)
				(type default)
			)
			(layer "F.SilkS")
		)
		(fp_line
			(start 0.7874 0.4064)
			(end -0.7874 0.4064)
			(stroke
				(width 0.1524)
				(type default)
			)
			(layer "F.SilkS")
		)
		(fp_line
			(start -0.67945 -0.305054)
			(end -0.12065 -0.305054)
			(stroke
				(width 0.1)
				(type default)
			)
			(layer "F.Fab")
		)
		(fp_line
			(start -0.67945 0.3048)
			(end -0.67945 -0.305054)
			(stroke
				(width 0.1)
				(type default)
			)
			(layer "F.Fab")
		)
		(fp_line
			(start -0.12065 -0.305054)
			(end -0.12065 -0.2794)
			(stroke
				(width 0.1)
				(type default)
			)
			(layer "F.Fab")
		)
		(fp_line
			(start -0.12065 -0.2794)
			(end 0.12065 -0.2794)
			(stroke
				(width 0.1)
				(type default)
			)
			(layer "F.Fab")
		)
		(fp_line
			(start -0.12065 0.2794)
			(end -0.12065 0.3048)
			(stroke
				(width 0.1)
				(type default)
			)
			(layer "F.Fab")
		)
		(fp_line
			(start -0.12065 0.3048)
			(end -0.67945 0.3048)
			(stroke
				(width 0.1)
				(type default)
			)
			(layer "F.Fab")
		)
		(fp_line
			(start 0.120396 0.2794)
			(end -0.12065 0.2794)
			(stroke
				(width 0.1)
				(type default)
			)
			(layer "F.Fab")
		)
		(fp_line
			(start 0.120396 0.3048)
			(end 0.120396 0.2794)
			(stroke
				(width 0.1)
				(type default)
			)
			(layer "F.Fab")
		)
		(fp_line
			(start 0.12065 -0.3048)
			(end 0.67945 -0.3048)
			(stroke
				(width 0.1)
				(type default)
			)
			(layer "F.Fab")
		)
		(fp_line
			(start 0.12065 -0.2794)
			(end 0.12065 -0.3048)
			(stroke
				(width 0.1)
				(type default)
			)
			(layer "F.Fab")
		)
		(fp_line
			(start 0.67945 -0.3048)
			(end 0.67945 0.3048)
			(stroke
				(width 0.1)
				(type default)
			)
			(layer "F.Fab")
		)
		(fp_line
			(start 0.67945 0.3048)
			(end 0.120396 0.3048)
			(stroke
				(width 0.1)
				(type default)
			)
			(layer "F.Fab")
		)
		(pad "1" smd circle
			(at -0.40005 0)
			(size 0 0)
			(layers "F.Cu" "F.Mask" "F.Paste")
			(net "PVCCD_HV_CPU1_ATSEN")
		)
		(pad "2" smd circle
			(at 0.40005 0)
			(size 0 0)
			(layers "F.Cu" "F.Mask" "F.Paste")
			(net "GND")
		)
	)
)
